(kicad_pcb
	(version 20260206)
	(generator "pcbnew")
	(generator_version "10.0")
	(general
		(thickness 1.6)
		(legacy_teardrops no)
	)
	(paper "A4")
	(title_block
		(title "baseboard — 13948-1b.1110WZS1818.brd")
		(comment 1 "Honey Badger (Wiwynn) / footprints 295-301 of 2523")
	)
	(layers
		(0 "F.Cu" signal "TOP")
		(4 "In1.Cu" signal "L2GND")
		(6 "In2.Cu" signal "L3")
		(8 "In3.Cu" signal "L4VCC")
		(10 "In4.Cu" signal "L5VCC")
		(12 "In5.Cu" signal "L6")
		(14 "In6.Cu" signal "L7GND")
		(2 "B.Cu" signal "BOTTOM")
		(9 "F.Adhes" user "F.Adhesive")
		(11 "B.Adhes" user "B.Adhesive")
		(13 "F.Paste" user "Package Geometry/Pastemask Top")
		(15 "B.Paste" user "Package Geometry/Pastemask Bottom")
		(5 "F.SilkS" user "Ref Des/Silkscreen Top")
		(7 "B.SilkS" user "Ref Des/Silkscreen Bottom")
		(1 "F.Mask" user "Board Geometry/Soldermask Top")
		(3 "B.Mask" user "Board Geometry/Soldermask Bottom")
		(17 "Dwgs.User" user "User.Drawings")
		(19 "Cmts.User" user "User.Comments")
		(21 "Eco1.User" user "User.Eco1")
		(23 "Eco2.User" user "User.Eco2")
		(25 "Edge.Cuts" user "Board Geometry/Outline")
		(27 "Margin" user)
		(31 "F.CrtYd" user "Package Geometry/Place Bound Top")
		(29 "B.CrtYd" user "Package Geometry/Place Bound Bottom")
		(35 "F.Fab" user "Ref Des/Assembly Top")
		(33 "B.Fab" user "Ref Des/Assembly Bottom")
	)
	(footprint ""
		(layer "F.Cu")
		(at 46.99 -230.886)
		(property "Reference" "C299"
			(at 0 0 0)
			(layer "F.SilkS")
			(hide yes)
			(effects
				(font
					(size 1.27 1.27)
				)
			)
		)
		(property "Value" "SC1U25V3KX-GP"
			(at 0 -2.8194 0)
			(unlocked yes)
			(layer "F.Fab")
			(hide yes)
			(effects
				(font
					(size 1.016 1.016)
					(thickness 0.1524)
				)
			)
		)
		(property "Device Type" "C603H36"
			(at 0 -4.3434 0)
			(unlocked yes)
			(layer "F.Fab")
			(hide yes)
			(effects
				(font
					(size 1.016 1.016)
					(thickness 0.1524)
				)
			)
		)
		(duplicate_pad_numbers_are_jumpers no)
		(fp_line
			(start 0.508 0)
			(end -0.508 0)
			(stroke
				(width 0.2032)
				(type default)
			)
			(layer "F.SilkS")
		)
		(fp_rect
			(start -0.5842 1.3335)
			(end 0.5842 -1.3335)
			(stroke
				(width 0)
				(type default)
			)
			(fill no)
			(layer "F.CrtYd")
		)
		(fp_rect
			(start -0.5842 1.3335)
			(end 0.5842 -1.3335)
			(stroke
				(width 0)
				(type default)
			)
			(fill no)
			(layer "F.Fab")
		)
		(pad "1" smd custom
			(at 0 -0.762)
			(size 0.2159 0.2159)
			(layers "F.Cu" "F.Mask" "F.Paste")
			(net "P12V_PCIE")
			(options
				(clearance outline)
				(anchor circle)
			)
			(primitives
				(gr_poly
					(pts
						(arc
							(start -0.3302 -0.4318)
							(mid -0.402042 -0.402042)
							(end -0.4318 -0.3302)
						)
						(arc
							(start -0.4318 0.3302)
							(mid -0.402042 0.402042)
							(end -0.3302 0.4318)
						)
						(arc
							(start 0.3302 0.4318)
							(mid 0.402042 0.402042)
							(end 0.4318 0.3302)
						)
						(arc
							(start 0.4318 -0.3302)
							(mid 0.402042 -0.402042)
							(end 0.3302 -0.4318)
						)
					)
					(width 0)
					(fill yes)
				)
			)
		)
		(pad "2" smd custom
			(at 0 0.762)
			(size 0.2159 0.2159)
			(layers "F.Cu" "F.Mask" "F.Paste")
			(net "GND")
			(options
				(clearance outline)
				(anchor circle)
			)
			(primitives
				(gr_poly
					(pts
						(arc
							(start -0.3302 -0.4318)
							(mid -0.402042 -0.402042)
							(end -0.4318 -0.3302)
						)
						(arc
							(start -0.4318 0.3302)
							(mid -0.402042 0.402042)
							(end -0.3302 0.4318)
						)
						(arc
							(start 0.3302 0.4318)
							(mid 0.402042 0.402042)
							(end 0.4318 0.3302)
						)
						(arc
							(start 0.4318 -0.3302)
							(mid 0.402042 -0.402042)
							(end 0.3302 -0.4318)
						)
					)
					(width 0)
					(fill yes)
				)
			)
		)
	)
	(footprint ""
		(layer "F.Cu")
		(at 109.074966 -64.2366)
		(property "Reference" "STP48"
			(at 0 0 0)
			(layer "F.SilkS")
			(hide yes)
			(effects
				(font
					(size 1.27 1.27)
				)
			)
		)
		(property "Value" "TPAD28"
			(at 0.0127 -1.8034 0)
			(unlocked yes)
			(layer "F.Fab")
			(hide yes)
			(effects
				(font
					(size 1.016 1.016)
					(thickness 0.1524)
				)
			)
		)
		(property "Device Type" "TPAD28"
			(at 0.0127 -3.3274 0)
			(unlocked yes)
			(layer "F.Fab")
			(hide yes)
			(effects
				(font
					(size 1.016 1.016)
					(thickness 0.1524)
				)
			)
		)
		(duplicate_pad_numbers_are_jumpers no)
		(fp_poly
			(pts
				(arc
					(start 0.3556 0)
					(mid -0.3556 0)
					(end 0.3556 0)
				)
			)
			(stroke
				(width 0)
				(type default)
			)
			(fill no)
			(layer "F.CrtYd")
		)
		(fp_poly
			(pts
				(arc
					(start 0.6096 0)
					(mid -0.6096 0)
					(end 0.6096 0)
				)
			)
			(stroke
				(width 0)
				(type default)
			)
			(fill no)
			(layer "F.Fab")
		)
		(pad "1" smd circle
			(at 0 0)
			(size 0.7112 0.7112)
			(layers "F.Cu" "F.Mask" "F.Paste")
			(net "JTAG_IOC_TDI")
		)
	)
	(footprint ""
		(layer "F.Cu")
		(at 90.525092 -134.389876)
		(property "Reference" "SU71"
			(at 0 0 0)
			(layer "F.SilkS")
			(hide yes)
			(effects
				(font
					(size 1.27 1.27)
				)
			)
		)
		(property "Value" "SNLVC8T245DGVR-GP"
			(at 0 -11.1252 0)
			(unlocked yes)
			(layer "F.Fab")
			(hide yes)
			(effects
				(font
					(size 1.016 1.016)
					(thickness 0.1524)
				)
			)
		)
		(property "Device Type" "TVSOP24H48"
			(at 0 -12.6492 0)
			(unlocked yes)
			(layer "F.Fab")
			(hide yes)
			(effects
				(font
					(size 1.016 1.016)
					(thickness 0.1524)
				)
			)
		)
		(duplicate_pad_numbers_are_jumpers no)
		(fp_line
			(start -2.9337 -1.397)
			(end -2.9337 1.397)
			(stroke
				(width 0.1524)
				(type default)
			)
			(layer "F.SilkS")
		)
		(fp_line
			(start -2.9337 -0.3683)
			(end -2.5654 0)
			(stroke
				(width 0.1524)
				(type default)
			)
			(layer "F.SilkS")
		)
		(fp_line
			(start -2.9337 1.397)
			(end 2.2987 1.397)
			(stroke
				(width 0.1524)
				(type default)
			)
			(layer "F.SilkS")
		)
		(fp_line
			(start -2.7559 1.397)
			(end -2.7559 3.8354)
			(stroke
				(width 0.508)
				(type default)
			)
			(layer "F.SilkS")
		)
		(fp_line
			(start -2.5654 0)
			(end -2.9337 0.3683)
			(stroke
				(width 0.1524)
				(type default)
			)
			(layer "F.SilkS")
		)
		(fp_line
			(start 2.2987 -1.397)
			(end -2.9337 -1.397)
			(stroke
				(width 0.1524)
				(type default)
			)
			(layer "F.SilkS")
		)
		(fp_line
			(start 2.2987 1.397)
			(end 2.2987 -1.397)
			(stroke
				(width 0.1524)
				(type default)
			)
			(layer "F.SilkS")
		)
		(fp_rect
			(start -3.0099 4.0894)
			(end 3.0099 -4.0894)
			(stroke
				(width 0)
				(type default)
			)
			(fill no)
			(layer "F.CrtYd")
		)
		(fp_poly
			(pts
				(xy -3.0099 -4.0894) (xy 3.0099 -4.0894) (xy 3.0099 4.0894) (xy -3.0099 4.0894)
			)
			(stroke
				(width 0)
				(type default)
			)
			(fill no)
			(layer "F.Fab")
		)
		(pad "1" smd rect
			(at -2.19964 2.8194)
			(size 0.2032 1.524)
			(layers "F.Cu" "F.Mask" "F.Paste")
			(net "P1V8_E")
		)
		(pad "2" smd rect
			(at -1.79959 2.8194)
			(size 0.2032 1.524)
			(layers "F.Cu" "F.Mask" "F.Paste")
			(net "GND")
		)
		(pad "3" smd rect
			(at -1.39954 2.8194)
			(size 0.2032 1.524)
			(layers "F.Cu" "F.Mask" "F.Paste")
			(net "EXP_GPIO_0")
		)
		(pad "4" smd rect
			(at -0.99949 2.8194)
			(size 0.2032 1.524)
			(layers "F.Cu" "F.Mask" "F.Paste")
			(net "EXP_GPIO_1")
		)
		(pad "5" smd rect
			(at -0.59944 2.8194)
			(size 0.2032 1.524)
			(layers "F.Cu" "F.Mask" "F.Paste")
			(net "EXP_GPIO_2")
		)
		(pad "6" smd rect
			(at -0.19939 2.8194)
			(size 0.2032 1.524)
			(layers "F.Cu" "F.Mask" "F.Paste")
			(net "EXP_GPIO_4")
		)
		(pad "7" smd rect
			(at 0.19939 2.8194)
			(size 0.2032 1.524)
			(layers "F.Cu" "F.Mask" "F.Paste")
			(net "EXP_GPIO_5")
		)
		(pad "8" smd rect
			(at 0.59944 2.8194)
			(size 0.2032 1.524)
			(layers "F.Cu" "F.Mask" "F.Paste")
			(net "EXP_GPIO_6")
		)
		(pad "9" smd rect
			(at 0.99949 2.8194)
			(size 0.2032 1.524)
			(layers "F.Cu" "F.Mask" "F.Paste")
			(net "EXP_GPIO_8")
		)
		(pad "10" smd rect
			(at 1.39954 2.8194)
			(size 0.2032 1.524)
			(layers "F.Cu" "F.Mask" "F.Paste")
			(net "EXP_GPIO_13")
		)
		(pad "11" smd rect
			(at 1.79959 2.8194)
			(size 0.2032 1.524)
			(layers "F.Cu" "F.Mask" "F.Paste")
			(net "GND")
		)
		(pad "12" smd rect
			(at 2.19964 2.8194)
			(size 0.2032 1.524)
			(layers "F.Cu" "F.Mask" "F.Paste")
			(net "GND")
		)
		(pad "13" smd rect
			(at 2.19964 -2.8194)
			(size 0.2032 1.524)
			(layers "F.Cu" "F.Mask" "F.Paste")
			(net "GND")
		)
		(pad "14" smd rect
			(at 1.79959 -2.8194)
			(size 0.2032 1.524)
			(layers "F.Cu" "F.Mask" "F.Paste")
			(net "EXP_HDD_PRE_INT_N")
		)
		(pad "15" smd rect
			(at 1.39954 -2.8194)
			(size 0.2032 1.524)
			(layers "F.Cu" "F.Mask" "F.Paste")
			(net "EXP_TRAY_ID")
		)
		(pad "16" smd rect
			(at 0.99949 -2.8194)
			(size 0.2032 1.524)
			(layers "F.Cu" "F.Mask" "F.Paste")
			(net "PEER_1B_2B_HB")
		)
		(pad "17" smd rect
			(at 0.59944 -2.8194)
			(size 0.2032 1.524)
			(layers "F.Cu" "F.Mask" "F.Paste")
			(net "PEER_1A_2A_HB")
		)
		(pad "18" smd rect
			(at 0.19939 -2.8194)
			(size 0.2032 1.524)
			(layers "F.Cu" "F.Mask" "F.Paste")
			(net "PEER_TRAY_R")
		)
		(pad "19" smd rect
			(at -0.19939 -2.8194)
			(size 0.2032 1.524)
			(layers "F.Cu" "F.Mask" "F.Paste")
			(net "EXP_SELF_TRAY")
		)
		(pad "20" smd rect
			(at -0.59944 -2.8194)
			(size 0.2032 1.524)
			(layers "F.Cu" "F.Mask" "F.Paste")
			(net "DPB_HW_REVISION")
		)
		(pad "21" smd rect
			(at -0.99949 -2.8194)
			(size 0.2032 1.524)
			(layers "F.Cu" "F.Mask" "F.Paste")
			(net "FCB_HW_REVISION")
		)
		(pad "22" smd rect
			(at -1.39954 -2.8194)
			(size 0.2032 1.524)
			(layers "F.Cu" "F.Mask" "F.Paste")
			(net "GND")
		)
		(pad "23" smd rect
			(at -1.79959 -2.8194)
			(size 0.2032 1.524)
			(layers "F.Cu" "F.Mask" "F.Paste")
			(net "P3V3_STBY")
		)
		(pad "24" smd rect
			(at -2.19964 -2.8194)
			(size 0.2032 1.524)
			(layers "F.Cu" "F.Mask" "F.Paste")
			(net "P3V3_STBY")
		)
	)
	(footprint ""
		(layer "F.Cu")
		(at 298.704 -191.897)
		(property "Reference" "R614"
			(at 0 0 0)
			(layer "F.SilkS")
			(hide yes)
			(effects
				(font
					(size 1.27 1.27)
				)
			)
		)
		(property "Value" "0R2J-2-GP"
			(at 0.064008 -3.993896 0)
			(unlocked yes)
			(layer "F.Fab")
			(hide yes)
			(effects
				(font
					(size 1.016 1.016)
					(thickness 0.1524)
				)
			)
		)
		(property "Device Type" "R402H16"
			(at 0.064008 -5.517896 0)
			(unlocked yes)
			(layer "F.Fab")
			(hide yes)
			(effects
				(font
					(size 1.016 1.016)
					(thickness 0.1524)
				)
			)
		)
		(duplicate_pad_numbers_are_jumpers no)
		(fp_line
			(start -0.508 -0.9398)
			(end -0.508 0.9398)
			(stroke
				(width 0.1524)
				(type default)
			)
			(layer "F.SilkS")
		)
		(fp_line
			(start 0.508 -0.9398)
			(end -0.508 -0.9398)
			(stroke
				(width 0.1524)
				(type default)
			)
			(layer "F.SilkS")
		)
		(fp_rect
			(start -0.508 0.9398)
			(end 0.508 -0.9398)
			(stroke
				(width 0)
				(type default)
			)
			(fill no)
			(layer "F.CrtYd")
		)
		(fp_rect
			(start -0.508 0.9398)
			(end 0.508 -0.9398)
			(stroke
				(width 0)
				(type default)
			)
			(fill no)
			(layer "F.Fab")
		)
		(pad "1" smd custom
			(at 0 -0.4445)
			(size 0.1397 0.1397)
			(layers "F.Cu" "F.Mask" "F.Paste")
			(net "SVR_ID0")
			(options
				(clearance outline)
				(anchor circle)
			)
			(primitives
				(gr_poly
					(pts
						(arc
							(start -0.1778 -0.2794)
							(mid -0.249642 -0.249642)
							(end -0.2794 -0.1778)
						)
						(arc
							(start -0.2794 0.1778)
							(mid -0.249642 0.249642)
							(end -0.1778 0.2794)
						)
						(arc
							(start 0.1778 0.2794)
							(mid 0.249642 0.249642)
							(end 0.2794 0.1778)
						)
						(arc
							(start 0.2794 -0.1778)
							(mid 0.249642 -0.249642)
							(end 0.1778 -0.2794)
						)
					)
					(width 0)
					(fill yes)
				)
			)
		)
		(pad "2" smd custom
			(at 0 0.4445)
			(size 0.1397 0.1397)
			(layers "F.Cu" "F.Mask" "F.Paste")
			(net "BMC0_TACH14")
			(options
				(clearance outline)
				(anchor circle)
			)
			(primitives
				(gr_poly
					(pts
						(arc
							(start -0.1778 -0.2794)
							(mid -0.249642 -0.249642)
							(end -0.2794 -0.1778)
						)
						(arc
							(start -0.2794 0.1778)
							(mid -0.249642 0.249642)
							(end -0.1778 0.2794)
						)
						(arc
							(start 0.1778 0.2794)
							(mid 0.249642 0.249642)
							(end 0.2794 0.1778)
						)
						(arc
							(start 0.2794 -0.1778)
							(mid 0.249642 -0.249642)
							(end 0.1778 -0.2794)
						)
					)
					(width 0)
					(fill yes)
				)
			)
		)
	)
	(footprint ""
		(layer "F.Cu")
		(at 62.23 -212.217 -90)
		(property "Reference" "R2099"
			(at 0 0 270)
			(layer "F.SilkS")
			(hide yes)
			(effects
				(font
					(size 1.27 1.27)
				)
			)
		)
		(property "Value" "39K2R2F-L-GP"
			(at 0.064008 -3.993896 270)
			(unlocked yes)
			(layer "F.Fab")
			(hide yes)
			(effects
				(font
					(size 1.016 1.016)
					(thickness 0.1524)
				)
			)
		)
		(property "Device Type" "R402H16"
			(at 0.064008 -5.517896 270)
			(unlocked yes)
			(layer "F.Fab")
			(hide yes)
			(effects
				(font
					(size 1.016 1.016)
					(thickness 0.1524)
				)
			)
		)
		(duplicate_pad_numbers_are_jumpers no)
		(fp_line
			(start -0.508 -0.9398)
			(end -0.508 0.9398)
			(stroke
				(width 0.1524)
				(type default)
			)
			(layer "F.SilkS")
		)
		(fp_line
			(start 0.508 -0.9398)
			(end -0.508 -0.9398)
			(stroke
				(width 0.1524)
				(type default)
			)
			(layer "F.SilkS")
		)
		(fp_rect
			(start -0.508 0.9398)
			(end 0.508 -0.9398)
			(stroke
				(width 0)
				(type default)
			)
			(fill no)
			(layer "F.CrtYd")
		)
		(fp_rect
			(start -0.508 0.9398)
			(end 0.508 -0.9398)
			(stroke
				(width 0)
				(type default)
			)
			(fill no)
			(layer "F.Fab")
		)
		(pad "1" smd custom
			(at 0 -0.4445 270)
			(size 0.1397 0.1397)
			(layers "F.Cu" "F.Mask" "F.Paste")
			(net "P12V")
			(options
				(clearance outline)
				(anchor circle)
			)
			(primitives
				(gr_poly
					(pts
						(arc
							(start -0.1778 -0.2794)
							(mid -0.249642 -0.249642)
							(end -0.2794 -0.1778)
						)
						(arc
							(start -0.2794 0.1778)
							(mid -0.249642 0.249642)
							(end -0.1778 0.2794)
						)
						(arc
							(start 0.1778 0.2794)
							(mid 0.249642 0.249642)
							(end 0.2794 0.1778)
						)
						(arc
							(start 0.2794 -0.1778)
							(mid 0.249642 -0.249642)
							(end 0.1778 -0.2794)
						)
					)
					(width 0)
					(fill yes)
				)
			)
		)
		(pad "2" smd custom
			(at 0 0.4445 270)
			(size 0.1397 0.1397)
			(layers "F.Cu" "F.Mask" "F.Paste")
			(net "MB0_P12V_PWRGOOD")
			(options
				(clearance outline)
				(anchor circle)
			)
			(primitives
				(gr_poly
					(pts
						(arc
							(start -0.1778 -0.2794)
							(mid -0.249642 -0.249642)
							(end -0.2794 -0.1778)
						)
						(arc
							(start -0.2794 0.1778)
							(mid -0.249642 0.249642)
							(end -0.1778 0.2794)
						)
						(arc
							(start 0.1778 0.2794)
							(mid 0.249642 0.249642)
							(end 0.2794 0.1778)
						)
						(arc
							(start 0.2794 -0.1778)
							(mid 0.249642 -0.249642)
							(end 0.1778 -0.2794)
						)
					)
					(width 0)
					(fill yes)
				)
			)
		)
	)
	(footprint ""
		(layer "F.Cu")
		(at 266.500864 -232.401872 90)
		(property "Reference" "PC92"
			(at 0 0 90)
			(layer "F.SilkS")
			(hide yes)
			(effects
				(font
					(size 1.27 1.27)
				)
			)
		)
		(property "Value" "SC10U6D3V5KX-1GP"
			(at -0.0762 -6.1214 90)
			(unlocked yes)
			(layer "F.Fab")
			(hide yes)
			(effects
				(font
					(size 1.016 1.016)
					(thickness 0.1524)
				)
			)
		)
		(property "Device Type" "C805H54"
			(at -0.0762 -8.1534 90)
			(unlocked yes)
			(layer "F.Fab")
			(hide yes)
			(effects
				(font
					(size 1.016 1.016)
					(thickness 0.1524)
				)
			)
		)
		(duplicate_pad_numbers_are_jumpers no)
		(fp_line
			(start 0.635 0)
			(end -0.635 0)
			(stroke
				(width 0.508)
				(type default)
			)
			(layer "F.SilkS")
		)
		(fp_rect
			(start -0.9652 1.778)
			(end 0.9652 -1.778)
			(stroke
				(width 0)
				(type default)
			)
			(fill no)
			(layer "F.CrtYd")
		)
		(fp_poly
			(pts
				(xy -0.9652 -1.778) (xy 0.9652 -1.778) (xy 0.9652 1.778) (xy -0.9652 1.778)
			)
			(stroke
				(width 0)
				(type default)
			)
			(fill no)
			(layer "F.Fab")
		)
		(pad "1" smd rect
			(at 0 -0.9652 90)
			(size 1.397 1.143)
			(layers "F.Cu" "F.Mask" "F.Paste")
			(net "TPS74801_P1V26_STBY_IN")
		)
		(pad "2" smd rect
			(at 0 0.9652 90)
			(size 1.397 1.143)
			(layers "F.Cu" "F.Mask" "F.Paste")
			(net "GND")
		)
	)
	(footprint ""
		(layer "F.Cu")
		(at 280.554684 -208.303876)
		(property "Reference" "U25"
			(at 0 0 0)
			(layer "F.SilkS")
			(hide yes)
			(effects
				(font
					(size 1.27 1.27)
				)
			)
		)
		(property "Value" "SN74LVC1G07DCKRG4-2-GP"
			(at -2.3368 -8.6868 0)
			(unlocked yes)
			(layer "F.Fab")
			(hide yes)
			(effects
				(font
					(size 1.016 1.016)
					(thickness 0.1524)
				)
			)
		)
		(property "Device Type" "SC70-5H44"
			(at -2.3114 -10.414 0)
			(unlocked yes)
			(layer "F.Fab")
			(hide yes)
			(effects
				(font
					(size 1.016 1.016)
					(thickness 0.1524)
				)
			)
		)
		(duplicate_pad_numbers_are_jumpers no)
		(fp_line
			(start -1.27 -1.7018)
			(end 1.27 -1.7018)
			(stroke
				(width 0.1524)
				(type default)
			)
			(layer "F.SilkS")
		)
		(fp_line
			(start -1.27 1.7018)
			(end -1.27 -1.7018)
			(stroke
				(width 0.1524)
				(type default)
			)
			(layer "F.SilkS")
		)
		(fp_line
			(start 0.6604 -1.8034)
			(end 1.3843 -1.8034)
			(stroke
				(width 0.3302)
				(type default)
			)
			(layer "F.SilkS")
		)
		(fp_line
			(start 1.27 -1.7018)
			(end 1.27 1.7018)
			(stroke
				(width 0.1524)
				(type default)
			)
			(layer "F.SilkS")
		)
		(fp_line
			(start 1.27 1.7018)
			(end -1.27 1.7018)
			(stroke
				(width 0.1524)
				(type default)
			)
			(layer "F.SilkS")
		)
		(fp_line
			(start 1.3843 -1.8034)
			(end 1.3843 -1.1176)
			(stroke
				(width 0.3302)
				(type default)
			)
			(layer "F.SilkS")
		)
		(fp_rect
			(start -1.524 1.9558)
			(end 1.524 -1.9558)
			(stroke
				(width 0)
				(type default)
			)
			(fill no)
			(layer "F.CrtYd")
		)
		(fp_poly
			(pts
				(xy -1.524 -1.9558) (xy 1.524 -1.9558) (xy 1.524 1.9558) (xy -1.524 1.9558)
			)
			(stroke
				(width 0)
				(type default)
			)
			(fill no)
			(layer "F.Fab")
		)
		(pad "1" smd rect
			(at 0.65024 -0.8255)
			(size 0.4064 1.2192)
			(layers "F.Cu" "F.Mask" "F.Paste")
			(net "Net_1371")
		)
		(pad "2" smd rect
			(at 0 -0.8255)
			(size 0.4064 1.2192)
			(layers "F.Cu" "F.Mask" "F.Paste")
			(net "FM_BMC_RESET_N")
		)
		(pad "3" smd rect
			(at -0.65024 -0.8255)
			(size 0.4064 1.2192)
			(layers "F.Cu" "F.Mask" "F.Paste")
			(net "GND")
		)
		(pad "4" smd rect
			(at -0.65024 0.8255)
			(size 0.4064 1.2192)
			(layers "F.Cu" "F.Mask" "F.Paste")
			(net "RST_BMC_DDR3_R_N")
		)
		(pad "5" smd rect
			(at 0.65024 0.8255)
			(size 0.4064 1.2192)
			(layers "F.Cu" "F.Mask" "F.Paste")
			(net "P3V3_STBY")
		)
	)
)
